(kicad_pcb
	(version 20260206)
	(generator "pcbnew")
	(generator_version "10.0")
	(general
		(thickness 1.6)
		(legacy_teardrops no)
	)
	(paper "A4")
	(title_block
		(title "Bryce Canyon_SCC_16316-1_OCP.brd")
		(comment 1 "Bryce Canyon / footprint 64 of 1561 (U1), pads 940-1020 of 1020")
	)
	(layers
		(0 "F.Cu" signal "TOP")
		(4 "In1.Cu" signal "L2GND")
		(6 "In2.Cu" signal "L3")
		(8 "In3.Cu" signal "L4VCC")
		(10 "In4.Cu" signal "L5VCC")
		(12 "In5.Cu" signal "L6")
		(14 "In6.Cu" signal "L7GND")
		(2 "B.Cu" signal "BOTTOM")
		(9 "F.Adhes" user "F.Adhesive")
		(11 "B.Adhes" user "B.Adhesive")
		(13 "F.Paste" user "Package Geometry/Pastemask Top")
		(15 "B.Paste" user "Package Geometry/Pastemask Bottom")
		(5 "F.SilkS" user "Ref Des/Silkscreen Top")
		(7 "B.SilkS" user "Ref Des/Silkscreen Bottom")
		(1 "F.Mask" user "Board Geometry/Soldermask Top")
		(3 "B.Mask" user "Board Geometry/Soldermask Bottom")
		(17 "Dwgs.User" user "User.Drawings")
		(19 "Cmts.User" user "User.Comments")
		(21 "Eco1.User" user "User.Eco1")
		(23 "Eco2.User" user "User.Eco2")
		(25 "Edge.Cuts" user "Board Geometry/Outline")
		(27 "Margin" user)
		(31 "F.CrtYd" user "Package Geometry/Place Bound Top")
		(29 "B.CrtYd" user "Package Geometry/Place Bound Bottom")
		(35 "F.Fab" user "Ref Des/Assembly Top")
		(33 "B.Fab" user "Ref Des/Assembly Bottom")
	)
	(footprint ""
		(layer "F.Cu")
		(at 115.000024 -67.00012)
		(property "Reference" "U1"
			(at 0 0 0)
			(layer "F.SilkS")
			(hide yes)
			(effects
				(font
					(size 1.27 1.27)
				)
			)
		)
		(property "Value" "LSISAS3X48-GP"
			(at -24.358092 -5.0292 0)
			(unlocked yes)
			(layer "F.Fab")
			(hide yes)
			(effects
				(font
					(size 1.016 1.016)
					(thickness 0.1524)
				)
			)
		)
		(property "Device Type" "BGA1020C33H83"
			(at -24.358092 -6.5532 0)
			(unlocked yes)
			(layer "F.Fab")
			(hide yes)
			(effects
				(font
					(size 1.016 1.016)
					(thickness 0.1524)
				)
			)
		)
		(duplicate_pad_numbers_are_jumpers no)
		(pad "V16" smd circle
			(at -0.500126 1.500124)
			(size 0.4572 0.4572)
			(layers "F.Cu" "F.Mask" "F.Paste")
			(net "GND")
		)
		(pad "V17" smd circle
			(at 0.500126 1.500124)
			(size 0.4572 0.4572)
			(layers "F.Cu" "F.Mask" "F.Paste")
			(net "P0V9")
		)
		(pad "V18" smd circle
			(at 1.500124 1.500124)
			(size 0.4572 0.4572)
			(layers "F.Cu" "F.Mask" "F.Paste")
			(net "GND")
		)
		(pad "V19" smd circle
			(at 2.500122 1.500124)
			(size 0.4572 0.4572)
			(layers "F.Cu" "F.Mask" "F.Paste")
			(net "P0V9")
		)
		(pad "V20" smd circle
			(at 3.50012 1.500124)
			(size 0.4572 0.4572)
			(layers "F.Cu" "F.Mask" "F.Paste")
			(net "GND")
		)
		(pad "V21" smd circle
			(at 4.500118 1.500124)
			(size 0.4572 0.4572)
			(layers "F.Cu" "F.Mask" "F.Paste")
			(net "GND")
		)
		(pad "V22" smd circle
			(at 5.500116 1.500124)
			(size 0.4572 0.4572)
			(layers "F.Cu" "F.Mask" "F.Paste")
			(net "GB_VDDH")
		)
		(pad "V23" smd circle
			(at 6.500114 1.500124)
			(size 0.4572 0.4572)
			(layers "F.Cu" "F.Mask" "F.Paste")
			(net "GND")
		)
		(pad "V24" smd circle
			(at 7.500112 1.500124)
			(size 0.4572 0.4572)
			(layers "F.Cu" "F.Mask" "F.Paste")
			(net "GND")
		)
		(pad "V25" smd circle
			(at 8.50011 1.500124)
			(size 0.4572 0.4572)
			(layers "F.Cu" "F.Mask" "F.Paste")
			(net "GND")
		)
		(pad "V26" smd circle
			(at 9.500108 1.500124)
			(size 0.4572 0.4572)
			(layers "F.Cu" "F.Mask" "F.Paste")
			(net "GND")
		)
		(pad "V27" smd circle
			(at 10.500106 1.500124)
			(size 0.4572 0.4572)
			(layers "F.Cu" "F.Mask" "F.Paste")
			(net "PHY_DPB_TO_SCC_C_0_DN")
		)
		(pad "V28" smd circle
			(at 11.500104 1.500124)
			(size 0.4572 0.4572)
			(layers "F.Cu" "F.Mask" "F.Paste")
			(net "PHY_DPB_TO_SCC_C_0_DP")
		)
		(pad "V29" smd circle
			(at 12.500102 1.500124)
			(size 0.4572 0.4572)
			(layers "F.Cu" "F.Mask" "F.Paste")
			(net "GB_VDDA")
		)
		(pad "V30" smd circle
			(at 13.5001 1.500124)
			(size 0.4572 0.4572)
			(layers "F.Cu" "F.Mask" "F.Paste")
			(net "PHY_SCC_TO_DPB_0_DN")
		)
		(pad "V31" smd circle
			(at 14.500098 1.500124)
			(size 0.4572 0.4572)
			(layers "F.Cu" "F.Mask" "F.Paste")
			(net "PHY_SCC_TO_DPB_0_DP")
		)
		(pad "V32" smd circle
			(at 15.500096 1.500124)
			(size 0.4572 0.4572)
			(layers "F.Cu" "F.Mask" "F.Paste")
			(net "GND")
		)
		(pad "W1" smd circle
			(at -15.500096 2.500122)
			(size 0.4572 0.4572)
			(layers "F.Cu" "F.Mask" "F.Paste")
			(net "GND")
		)
		(pad "W2" smd circle
			(at -14.500098 2.500122)
			(size 0.4572 0.4572)
			(layers "F.Cu" "F.Mask" "F.Paste")
			(net "GND")
		)
		(pad "W3" smd circle
			(at -13.5001 2.500122)
			(size 0.4572 0.4572)
			(layers "F.Cu" "F.Mask" "F.Paste")
			(net "GND")
		)
		(pad "W4" smd circle
			(at -12.500102 2.500122)
			(size 0.4572 0.4572)
			(layers "F.Cu" "F.Mask" "F.Paste")
			(net "GND")
		)
		(pad "W5" smd circle
			(at -11.500104 2.500122)
			(size 0.4572 0.4572)
			(layers "F.Cu" "F.Mask" "F.Paste")
			(net "GND")
		)
		(pad "W6" smd circle
			(at -10.500106 2.500122)
			(size 0.4572 0.4572)
			(layers "F.Cu" "F.Mask" "F.Paste")
			(net "GND")
		)
		(pad "W7" smd circle
			(at -9.500108 2.500122)
			(size 0.4572 0.4572)
			(layers "F.Cu" "F.Mask" "F.Paste")
			(net "DRIVE_13_ACT")
		)
		(pad "W8" smd circle
			(at -8.50011 2.500122)
			(size 0.4572 0.4572)
			(layers "F.Cu" "F.Mask" "F.Paste")
			(net "DRIVE_16_ACT")
		)
		(pad "W9" smd circle
			(at -7.500112 2.500122)
			(size 0.4572 0.4572)
			(layers "F.Cu" "F.Mask" "F.Paste")
			(net "DRIVE_21_ACT")
		)
		(pad "W10" smd circle
			(at -6.500114 2.500122)
			(size 0.4572 0.4572)
			(layers "F.Cu" "F.Mask" "F.Paste")
			(net "P1V8_E")
		)
		(pad "W11" smd circle
			(at -5.500116 2.500122)
			(size 0.4572 0.4572)
			(layers "F.Cu" "F.Mask" "F.Paste")
			(net "GND")
		)
		(pad "W12" smd circle
			(at -4.500118 2.500122)
			(size 0.4572 0.4572)
			(layers "F.Cu" "F.Mask" "F.Paste")
			(net "P0V9")
		)
		(pad "W13" smd circle
			(at -3.50012 2.500122)
			(size 0.4572 0.4572)
			(layers "F.Cu" "F.Mask" "F.Paste")
			(net "GND")
		)
		(pad "W14" smd circle
			(at -2.500122 2.500122)
			(size 0.4572 0.4572)
			(layers "F.Cu" "F.Mask" "F.Paste")
			(net "P0V9")
		)
		(pad "W15" smd circle
			(at -1.500124 2.500122)
			(size 0.4572 0.4572)
			(layers "F.Cu" "F.Mask" "F.Paste")
			(net "GND")
		)
		(pad "W16" smd circle
			(at -0.500126 2.500122)
			(size 0.4572 0.4572)
			(layers "F.Cu" "F.Mask" "F.Paste")
			(net "P0V9")
		)
		(pad "W17" smd circle
			(at 0.500126 2.500122)
			(size 0.4572 0.4572)
			(layers "F.Cu" "F.Mask" "F.Paste")
			(net "GND")
		)
		(pad "W18" smd circle
			(at 1.500124 2.500122)
			(size 0.4572 0.4572)
			(layers "F.Cu" "F.Mask" "F.Paste")
			(net "P0V9")
		)
		(pad "W19" smd circle
			(at 2.500122 2.500122)
			(size 0.4572 0.4572)
			(layers "F.Cu" "F.Mask" "F.Paste")
			(net "GND")
		)
		(pad "W20" smd circle
			(at 3.50012 2.500122)
			(size 0.4572 0.4572)
			(layers "F.Cu" "F.Mask" "F.Paste")
			(net "P0V9")
		)
		(pad "W21" smd circle
			(at 4.500118 2.500122)
			(size 0.4572 0.4572)
			(layers "F.Cu" "F.Mask" "F.Paste")
			(net "GND")
		)
		(pad "W22" smd circle
			(at 5.500116 2.500122)
			(size 0.4572 0.4572)
			(layers "F.Cu" "F.Mask" "F.Paste")
			(net "GB_VDDH")
		)
		(pad "W23" smd circle
			(at 6.500114 2.500122)
			(size 0.4572 0.4572)
			(layers "F.Cu" "F.Mask" "F.Paste")
			(net "GND")
		)
		(pad "W24" smd circle
			(at 7.500112 2.500122)
			(size 0.4572 0.4572)
			(layers "F.Cu" "F.Mask" "F.Paste")
			(net "GB_VDDA")
		)
		(pad "W25" smd circle
			(at 8.50011 2.500122)
			(size 0.4572 0.4572)
			(layers "F.Cu" "F.Mask" "F.Paste")
			(net "GND")
		)
		(pad "W26" smd circle
			(at 9.500108 2.500122)
			(size 0.4572 0.4572)
			(layers "F.Cu" "F.Mask" "F.Paste")
			(net "GB_VDDA")
		)
		(pad "W27" smd circle
			(at 10.500106 2.500122)
			(size 0.4572 0.4572)
			(layers "F.Cu" "F.Mask" "F.Paste")
			(net "PHY_DPB_TO_SCC_C_31_DN")
		)
		(pad "W28" smd circle
			(at 11.500104 2.500122)
			(size 0.4572 0.4572)
			(layers "F.Cu" "F.Mask" "F.Paste")
			(net "PHY_DPB_TO_SCC_C_31_DP")
		)
		(pad "W29" smd circle
			(at 12.500102 2.500122)
			(size 0.4572 0.4572)
			(layers "F.Cu" "F.Mask" "F.Paste")
			(net "GND")
		)
		(pad "W30" smd circle
			(at 13.5001 2.500122)
			(size 0.4572 0.4572)
			(layers "F.Cu" "F.Mask" "F.Paste")
			(net "GB_VDDA")
		)
		(pad "W31" smd circle
			(at 14.500098 2.500122)
			(size 0.4572 0.4572)
			(layers "F.Cu" "F.Mask" "F.Paste")
			(net "PHY_SCC_TO_DPB_31_DN")
		)
		(pad "W32" smd circle
			(at 15.500096 2.500122)
			(size 0.4572 0.4572)
			(layers "F.Cu" "F.Mask" "F.Paste")
			(net "PHY_SCC_TO_DPB_31_DP")
		)
		(pad "Y1" smd circle
			(at -15.500096 3.50012)
			(size 0.4572 0.4572)
			(layers "F.Cu" "F.Mask" "F.Paste")
			(net "DRIVE_12_ACT")
		)
		(pad "Y2" smd circle
			(at -14.500098 3.50012)
			(size 0.4572 0.4572)
			(layers "F.Cu" "F.Mask" "F.Paste")
			(net "DRIVE_14_ACT")
		)
		(pad "Y3" smd circle
			(at -13.5001 3.50012)
			(size 0.4572 0.4572)
			(layers "F.Cu" "F.Mask" "F.Paste")
			(net "GND")
		)
		(pad "Y4" smd circle
			(at -12.500102 3.50012)
			(size 0.4572 0.4572)
			(layers "F.Cu" "F.Mask" "F.Paste")
			(net "DRIVE_15_ACT")
		)
		(pad "Y5" smd circle
			(at -11.500104 3.50012)
			(size 0.4572 0.4572)
			(layers "F.Cu" "F.Mask" "F.Paste")
			(net "DRIVE_18_ACT")
		)
		(pad "Y6" smd circle
			(at -10.500106 3.50012)
			(size 0.4572 0.4572)
			(layers "F.Cu" "F.Mask" "F.Paste")
			(net "P1V8_E")
		)
		(pad "Y7" smd circle
			(at -9.500108 3.50012)
			(size 0.4572 0.4572)
			(layers "F.Cu" "F.Mask" "F.Paste")
			(net "DRIVE_17_ACT")
		)
		(pad "Y8" smd circle
			(at -8.50011 3.50012)
			(size 0.4572 0.4572)
			(layers "F.Cu" "F.Mask" "F.Paste")
			(net "DRIVE_26_ACT")
		)
		(pad "Y9" smd circle
			(at -7.500112 3.50012)
			(size 0.4572 0.4572)
			(layers "F.Cu" "F.Mask" "F.Paste")
			(net "DRIVE_31_ACT")
		)
		(pad "Y10" smd circle
			(at -6.500114 3.50012)
			(size 0.4572 0.4572)
			(layers "F.Cu" "F.Mask" "F.Paste")
			(net "XTAL_VDDA09")
		)
		(pad "Y11" smd circle
			(at -5.500116 3.50012)
			(size 0.4572 0.4572)
			(layers "F.Cu" "F.Mask" "F.Paste")
			(net "GND")
		)
		(pad "Y12" smd circle
			(at -4.500118 3.50012)
			(size 0.4572 0.4572)
			(layers "F.Cu" "F.Mask" "F.Paste")
			(net "GND")
		)
		(pad "Y13" smd circle
			(at -3.50012 3.50012)
			(size 0.4572 0.4572)
			(layers "F.Cu" "F.Mask" "F.Paste")
			(net "GND")
		)
		(pad "Y14" smd circle
			(at -2.500122 3.50012)
			(size 0.4572 0.4572)
			(layers "F.Cu" "F.Mask" "F.Paste")
			(net "GND")
		)
		(pad "Y15" smd circle
			(at -1.500124 3.50012)
			(size 0.4572 0.4572)
			(layers "F.Cu" "F.Mask" "F.Paste")
			(net "GND")
		)
		(pad "Y16" smd circle
			(at -0.500126 3.50012)
			(size 0.4572 0.4572)
			(layers "F.Cu" "F.Mask" "F.Paste")
			(net "GND")
		)
		(pad "Y17" smd circle
			(at 0.500126 3.50012)
			(size 0.4572 0.4572)
			(layers "F.Cu" "F.Mask" "F.Paste")
			(net "GND")
		)
		(pad "Y18" smd circle
			(at 1.500124 3.50012)
			(size 0.4572 0.4572)
			(layers "F.Cu" "F.Mask" "F.Paste")
			(net "GND")
		)
		(pad "Y19" smd circle
			(at 2.500122 3.50012)
			(size 0.4572 0.4572)
			(layers "F.Cu" "F.Mask" "F.Paste")
			(net "GND")
		)
		(pad "Y20" smd circle
			(at 3.50012 3.50012)
			(size 0.4572 0.4572)
			(layers "F.Cu" "F.Mask" "F.Paste")
			(net "GND")
		)
		(pad "Y21" smd circle
			(at 4.500118 3.50012)
			(size 0.4572 0.4572)
			(layers "F.Cu" "F.Mask" "F.Paste")
			(net "GND")
		)
		(pad "Y22" smd circle
			(at 5.500116 3.50012)
			(size 0.4572 0.4572)
			(layers "F.Cu" "F.Mask" "F.Paste")
			(net "GB_VDDH")
		)
		(pad "Y23" smd circle
			(at 6.500114 3.50012)
			(size 0.4572 0.4572)
			(layers "F.Cu" "F.Mask" "F.Paste")
			(net "GND")
		)
		(pad "Y24" smd circle
			(at 7.500112 3.50012)
			(size 0.4572 0.4572)
			(layers "F.Cu" "F.Mask" "F.Paste")
			(net "GND")
		)
		(pad "Y25" smd circle
			(at 8.50011 3.50012)
			(size 0.4572 0.4572)
			(layers "F.Cu" "F.Mask" "F.Paste")
			(net "GND")
		)
		(pad "Y26" smd circle
			(at 9.500108 3.50012)
			(size 0.4572 0.4572)
			(layers "F.Cu" "F.Mask" "F.Paste")
			(net "GND")
		)
		(pad "Y27" smd circle
			(at 10.500106 3.50012)
			(size 0.4572 0.4572)
			(layers "F.Cu" "F.Mask" "F.Paste")
			(net "PHY_DPB_TO_SCC_C_30_DN")
		)
		(pad "Y28" smd circle
			(at 11.500104 3.50012)
			(size 0.4572 0.4572)
			(layers "F.Cu" "F.Mask" "F.Paste")
			(net "PHY_DPB_TO_SCC_C_30_DP")
		)
		(pad "Y29" smd circle
			(at 12.500102 3.50012)
			(size 0.4572 0.4572)
			(layers "F.Cu" "F.Mask" "F.Paste")
			(net "GB_VDDA")
		)
		(pad "Y30" smd circle
			(at 13.5001 3.50012)
			(size 0.4572 0.4572)
			(layers "F.Cu" "F.Mask" "F.Paste")
			(net "PHY_SCC_TO_DPB_30_DN")
		)
		(pad "Y31" smd circle
			(at 14.500098 3.50012)
			(size 0.4572 0.4572)
			(layers "F.Cu" "F.Mask" "F.Paste")
			(net "PHY_SCC_TO_DPB_30_DP")
		)
		(pad "Y32" smd circle
			(at 15.500096 3.50012)
			(size 0.4572 0.4572)
			(layers "F.Cu" "F.Mask" "F.Paste")
			(net "GND")
		)
	)
)
